# SCM (Grand Teton) — schematic netlist excerpt (pin names and nets, part order shuffled) for the footprints in the layout excerpt that follows; sources: Cadence DE-HDL packaged netlist, KiCad conversion of 12092022_DA0F0TMDCD0_F0T_Management_Board_D_brd_V3_OCP.brd

R406  Q_RES  10K 1% CHIP  pkg 0402LF  page 54 : A = P3V3_AUX ; B = PWRGD_P1V8_AUX_R
R748  Q_RES  0 5% CHIP  pkg 0402LF  page 36 : A = PU_FPGA_NCONFIG ; B = RST_ROT_CPU_N

(kicad_pcb
	(version 20260206)
	(generator "pcbnew")
	(generator_version "10.0")
	(general
		(thickness 1.6)
		(legacy_teardrops no)
	)
	(paper "A4")
	(title_block
		(title "12092022_DA0F0TMDCD0_F0T_Management_Board_D_brd_V3_OCP.brd")
		(comment 1 "Grand Teton / footprints 17-18 of 1440")
	)
	(layers
		(0 "F.Cu" signal "TOP")
		(4 "In1.Cu" signal "GND")
		(6 "In2.Cu" signal "IN1")
		(8 "In3.Cu" signal "GND1")
		(10 "In4.Cu" signal "IN2")
		(12 "In5.Cu" signal "VCC")
		(14 "In6.Cu" signal "VCC1")
		(16 "In7.Cu" signal "IN3")
		(18 "In8.Cu" signal "GND2")
		(20 "In9.Cu" signal "IN4")
		(22 "In10.Cu" signal "GND3")
		(2 "B.Cu" signal "BOTTOM")
		(9 "F.Adhes" user "F.Adhesive")
		(11 "B.Adhes" user "B.Adhesive")
		(13 "F.Paste" user "Package Geometry/Pastemask Top")
		(15 "B.Paste" user "Package Geometry/Pastemask Bottom")
		(5 "F.SilkS" user "Ref Des/Silkscreen Top")
		(7 "B.SilkS" user "Ref Des/Silkscreen Bottom")
		(1 "F.Mask" user "Board Geometry/Soldermask Top")
		(3 "B.Mask" user "Board Geometry/Soldermask Bottom")
		(17 "Dwgs.User" user "User.Drawings")
		(19 "Cmts.User" user "User.Comments")
		(21 "Eco1.User" user "User.Eco1")
		(23 "Eco2.User" user "User.Eco2")
		(25 "Edge.Cuts" user "Board Geometry/Outline")
		(27 "Margin" user)
		(31 "F.CrtYd" user "Package Geometry/Place Bound Top")
		(29 "B.CrtYd" user "Package Geometry/Place Bound Bottom")
		(35 "F.Fab" user "Ref Des/Assembly Top")
		(33 "B.Fab" user "Ref Des/Assembly Bottom")
	)
	(footprint ""
		(layer "F.Cu")
		(at 30.1752 -90.3478 90)
		(property "Reference" "R748"
			(at 0 0 90)
			(layer "F.SilkS")
			(hide yes)
			(effects
				(font
					(size 1.27 1.27)
				)
			)
		)
		(property "Value" ""
			(at 0 0 90)
			(layer "F.Fab")
			(effects
				(font
					(size 1.27 1.27)
				)
			)
		)
		(duplicate_pad_numbers_are_jumpers no)
		(fp_line
			(start 0.7874 -0.4064)
			(end 0.7874 0.4064)
			(stroke
				(width 0.1524)
				(type default)
			)
			(layer "F.SilkS")
		)
		(fp_line
			(start -0.7874 -0.4064)
			(end 0.7874 -0.4064)
			(stroke
				(width 0.1524)
				(type default)
			)
			(layer "F.SilkS")
		)
		(fp_line
			(start 0.7874 0.4064)
			(end -0.7874 0.4064)
			(stroke
				(width 0.1524)
				(type default)
			)
			(layer "F.SilkS")
		)
		(fp_line
			(start -0.7874 0.4064)
			(end -0.7874 -0.4064)
			(stroke
				(width 0.1524)
				(type default)
			)
			(layer "F.SilkS")
		)
		(fp_line
			(start -0.12065 -0.305054)
			(end -0.12065 -0.2794)
			(stroke
				(width 0.1)
				(type default)
			)
			(layer "F.Fab")
		)
		(fp_line
			(start -0.67945 -0.305054)
			(end -0.12065 -0.305054)
			(stroke
				(width 0.1)
				(type default)
			)
			(layer "F.Fab")
		)
		(fp_line
			(start 0.67945 -0.3048)
			(end 0.67945 0.3048)
			(stroke
				(width 0.1)
				(type default)
			)
			(layer "F.Fab")
		)
		(fp_line
			(start 0.12065 -0.3048)
			(end 0.67945 -0.3048)
			(stroke
				(width 0.1)
				(type default)
			)
			(layer "F.Fab")
		)
		(fp_line
			(start 0.12065 -0.2794)
			(end 0.12065 -0.3048)
			(stroke
				(width 0.1)
				(type default)
			)
			(layer "F.Fab")
		)
		(fp_line
			(start -0.12065 -0.2794)
			(end 0.12065 -0.2794)
			(stroke
				(width 0.1)
				(type default)
			)
			(layer "F.Fab")
		)
		(fp_line
			(start 0.120396 0.2794)
			(end -0.12065 0.2794)
			(stroke
				(width 0.1)
				(type default)
			)
			(layer "F.Fab")
		)
		(fp_line
			(start -0.12065 0.2794)
			(end -0.12065 0.3048)
			(stroke
				(width 0.1)
				(type default)
			)
			(layer "F.Fab")
		)
		(fp_line
			(start 0.67945 0.3048)
			(end 0.120396 0.3048)
			(stroke
				(width 0.1)
				(type default)
			)
			(layer "F.Fab")
		)
		(fp_line
			(start 0.120396 0.3048)
			(end 0.120396 0.2794)
			(stroke
				(width 0.1)
				(type default)
			)
			(layer "F.Fab")
		)
		(fp_line
			(start -0.12065 0.3048)
			(end -0.67945 0.3048)
			(stroke
				(width 0.1)
				(type default)
			)
			(layer "F.Fab")
		)
		(fp_line
			(start -0.67945 0.3048)
			(end -0.67945 -0.305054)
			(stroke
				(width 0.1)
				(type default)
			)
			(layer "F.Fab")
		)
		(pad "1" smd circle
			(at -0.40005 0 90)
			(size 0 0)
			(layers "F.Cu" "F.Mask" "F.Paste")
			(net "PU_FPGA_NCONFIG")
		)
		(pad "2" smd circle
			(at 0.40005 0 90)
			(size 0 0)
			(layers "F.Cu" "F.Mask" "F.Paste")
			(net "RST_ROT_CPU_N")
		)
	)
	(footprint ""
		(layer "F.Cu")
		(at 40.132 -56.896 180)
		(property "Reference" "R406"
			(at 0 0 180)
			(layer "F.SilkS")
			(hide yes)
			(effects
				(font
					(size 1.27 1.27)
				)
			)
		)
		(property "Value" ""
			(at 0 0 180)
			(layer "F.Fab")
			(effects
				(font
					(size 1.27 1.27)
				)
			)
		)
		(duplicate_pad_numbers_are_jumpers no)
		(fp_line
			(start 0.7874 0.4064)
			(end -0.7874 0.4064)
			(stroke
				(width 0.1524)
				(type default)
			)
			(layer "F.SilkS")
		)
		(fp_line
			(start 0.7874 -0.4064)
			(end 0.7874 0.4064)
			(stroke
				(width 0.1524)
				(type default)
			)
			(layer "F.SilkS")
		)
		(fp_line
			(start -0.7874 0.4064)
			(end -0.7874 -0.4064)
			(stroke
				(width 0.1524)
				(type default)
			)
			(layer "F.SilkS")
		)
		(fp_line
			(start -0.7874 -0.4064)
			(end 0.7874 -0.4064)
			(stroke
				(width 0.1524)
				(type default)
			)
			(layer "F.SilkS")
		)
		(fp_line
			(start 0.67945 0.3048)
			(end 0.120396 0.3048)
			(stroke
				(width 0.1)
				(type default)
			)
			(layer "F.Fab")
		)
		(fp_line
			(start 0.67945 -0.3048)
			(end 0.67945 0.3048)
			(stroke
				(width 0.1)
				(type default)
			)
			(layer "F.Fab")
		)
		(fp_line
			(start 0.12065 -0.2794)
			(end 0.12065 -0.3048)
			(stroke
				(width 0.1)
				(type default)
			)
			(layer "F.Fab")
		)
		(fp_line
			(start 0.12065 -0.3048)
			(end 0.67945 -0.3048)
			(stroke
				(width 0.1)
				(type default)
			)
			(layer "F.Fab")
		)
		(fp_line
			(start 0.120396 0.3048)
			(end 0.120396 0.2794)
			(stroke
				(width 0.1)
				(type default)
			)
			(layer "F.Fab")
		)
		(fp_line
			(start 0.120396 0.2794)
			(end -0.12065 0.2794)
			(stroke
				(width 0.1)
				(type default)
			)
			(layer "F.Fab")
		)
		(fp_line
			(start -0.12065 0.3048)
			(end -0.67945 0.3048)
			(stroke
				(width 0.1)
				(type default)
			)
			(layer "F.Fab")
		)
		(fp_line
			(start -0.12065 0.2794)
			(end -0.12065 0.3048)
			(stroke
				(width 0.1)
				(type default)
			)
			(layer "F.Fab")
		)
		(fp_line
			(start -0.12065 -0.2794)
			(end 0.12065 -0.2794)
			(stroke
				(width 0.1)
				(type default)
			)
			(layer "F.Fab")
		)
		(fp_line
			(start -0.12065 -0.305054)
			(end -0.12065 -0.2794)
			(stroke
				(width 0.1)
				(type default)
			)
			(layer "F.Fab")
		)
		(fp_line
			(start -0.67945 0.3048)
			(end -0.67945 -0.305054)
			(stroke
				(width 0.1)
				(type default)
			)
			(layer "F.Fab")
		)
		(fp_line
			(start -0.67945 -0.305054)
			(end -0.12065 -0.305054)
			(stroke
				(width 0.1)
				(type default)
			)
			(layer "F.Fab")
		)
		(pad "1" smd circle
			(at -0.40005 0 180)
			(size 0 0)
			(layers "F.Cu" "F.Mask" "F.Paste")
			(net "P3V3_AUX")
		)
		(pad "2" smd circle
			(at 0.40005 0 180)
			(size 0 0)
			(layers "F.Cu" "F.Mask" "F.Paste")
			(net "PWRGD_P1V8_AUX_R")
		)
	)
)
